# T6G (Grand Teton) — schematic netlist excerpt (pin names and nets, part order shuffled) for the footprints in the layout excerpt that follows; sources: Cadence DE-HDL packaged netlist, KiCad conversion of 04192023_DAF0TMB3IC0_F0TG_MB_C_brd_V02_OCP.brd

PC2230  Q_CAP  1UF 25V 10% X6S  pkg C0402  page 152 : A = P12V_AUX ; B = GND
R213  Q_RES  0 5% CHIP  pkg 0402LF  page 28 : A = SMB_CPU_5_R_SDA ; B = SMB_CPU_5_SDA

(kicad_pcb
	(version 20260206)
	(generator "pcbnew")
	(generator_version "10.0")
	(general
		(thickness 1.6)
		(legacy_teardrops no)
	)
	(paper "A4")
	(title_block
		(title "04192023_DAF0TMB3IC0_F0TG_MB_C_brd_V02_OCP.brd")
		(comment 1 "Grand Teton / footprints 4666-4667 of 8354")
	)
	(layers
		(0 "F.Cu" signal "TOP")
		(4 "In1.Cu" signal "GND")
		(6 "In2.Cu" signal "IN1")
		(8 "In3.Cu" signal "GND1")
		(10 "In4.Cu" signal "IN2")
		(12 "In5.Cu" signal "GND2")
		(14 "In6.Cu" signal "IN3")
		(16 "In7.Cu" signal "GND3")
		(18 "In8.Cu" signal "VCC")
		(20 "In9.Cu" signal "VCC1")
		(22 "In10.Cu" signal "GND4")
		(24 "In11.Cu" signal "IN4")
		(26 "In12.Cu" signal "GND5")
		(28 "In13.Cu" signal "IN5")
		(30 "In14.Cu" signal "GND6")
		(32 "In15.Cu" signal "IN6")
		(34 "In16.Cu" signal "GND7")
		(2 "B.Cu" signal "BOTTOM")
		(9 "F.Adhes" user "F.Adhesive")
		(11 "B.Adhes" user "B.Adhesive")
		(13 "F.Paste" user "Package Geometry/Pastemask Top")
		(15 "B.Paste" user "Package Geometry/Pastemask Bottom")
		(5 "F.SilkS" user "Ref Des/Silkscreen Top")
		(7 "B.SilkS" user "Ref Des/Silkscreen Bottom")
		(1 "F.Mask" user "Board Geometry/Soldermask Top")
		(3 "B.Mask" user "Board Geometry/Soldermask Bottom")
		(17 "Dwgs.User" user "User.Drawings")
		(19 "Cmts.User" user "User.Comments")
		(21 "Eco1.User" user "User.Eco1")
		(23 "Eco2.User" user "User.Eco2")
		(25 "Edge.Cuts" user "Board Geometry/Outline")
		(27 "Margin" user)
		(31 "F.CrtYd" user "Package Geometry/Place Bound Top")
		(29 "B.CrtYd" user "Package Geometry/Place Bound Bottom")
		(35 "F.Fab" user "Ref Des/Assembly Top")
		(33 "B.Fab" user "Ref Des/Assembly Bottom")
	)
	(footprint ""
		(layer "F.Cu")
		(at 393.363958 -325.675752)
		(property "Reference" "R213"
			(at 0 0 0)
			(layer "F.SilkS")
			(hide yes)
			(effects
				(font
					(size 1.27 1.27)
				)
			)
		)
		(property "Value" ""
			(at 0 0 0)
			(layer "F.Fab")
			(effects
				(font
					(size 1.27 1.27)
				)
			)
		)
		(duplicate_pad_numbers_are_jumpers no)
		(fp_line
			(start -0.7874 -0.4064)
			(end 0.7874 -0.4064)
			(stroke
				(width 0.1524)
				(type default)
			)
			(layer "F.SilkS")
		)
		(fp_line
			(start -0.7874 0.4064)
			(end -0.7874 -0.4064)
			(stroke
				(width 0.1524)
				(type default)
			)
			(layer "F.SilkS")
		)
		(fp_line
			(start 0.7874 -0.4064)
			(end 0.7874 0.4064)
			(stroke
				(width 0.1524)
				(type default)
			)
			(layer "F.SilkS")
		)
		(fp_line
			(start 0.7874 0.4064)
			(end -0.7874 0.4064)
			(stroke
				(width 0.1524)
				(type default)
			)
			(layer "F.SilkS")
		)
		(fp_line
			(start -0.67945 -0.305054)
			(end -0.12065 -0.305054)
			(stroke
				(width 0.1)
				(type default)
			)
			(layer "F.Fab")
		)
		(fp_line
			(start -0.67945 0.3048)
			(end -0.67945 -0.305054)
			(stroke
				(width 0.1)
				(type default)
			)
			(layer "F.Fab")
		)
		(fp_line
			(start -0.12065 -0.305054)
			(end -0.12065 -0.2794)
			(stroke
				(width 0.1)
				(type default)
			)
			(layer "F.Fab")
		)
		(fp_line
			(start -0.12065 -0.2794)
			(end 0.12065 -0.2794)
			(stroke
				(width 0.1)
				(type default)
			)
			(layer "F.Fab")
		)
		(fp_line
			(start -0.12065 0.2794)
			(end -0.12065 0.3048)
			(stroke
				(width 0.1)
				(type default)
			)
			(layer "F.Fab")
		)
		(fp_line
			(start -0.12065 0.3048)
			(end -0.67945 0.3048)
			(stroke
				(width 0.1)
				(type default)
			)
			(layer "F.Fab")
		)
		(fp_line
			(start 0.120396 0.2794)
			(end -0.12065 0.2794)
			(stroke
				(width 0.1)
				(type default)
			)
			(layer "F.Fab")
		)
		(fp_line
			(start 0.120396 0.3048)
			(end 0.120396 0.2794)
			(stroke
				(width 0.1)
				(type default)
			)
			(layer "F.Fab")
		)
		(fp_line
			(start 0.12065 -0.3048)
			(end 0.67945 -0.3048)
			(stroke
				(width 0.1)
				(type default)
			)
			(layer "F.Fab")
		)
		(fp_line
			(start 0.12065 -0.2794)
			(end 0.12065 -0.3048)
			(stroke
				(width 0.1)
				(type default)
			)
			(layer "F.Fab")
		)
		(fp_line
			(start 0.67945 -0.3048)
			(end 0.67945 0.3048)
			(stroke
				(width 0.1)
				(type default)
			)
			(layer "F.Fab")
		)
		(fp_line
			(start 0.67945 0.3048)
			(end 0.120396 0.3048)
			(stroke
				(width 0.1)
				(type default)
			)
			(layer "F.Fab")
		)
		(pad "1" smd circle
			(at -0.40005 0)
			(size 0 0)
			(layers "F.Cu" "F.Mask" "F.Paste")
			(net "SMB_CPU_5_R_SDA")
		)
		(pad "2" smd circle
			(at 0.40005 0)
			(size 0 0)
			(layers "F.Cu" "F.Mask" "F.Paste")
			(net "SMB_CPU_5_SDA")
		)
	)
	(footprint ""
		(layer "F.Cu")
		(at 187.28436 -29.77769 -90)
		(property "Reference" "PC2230"
			(at 0 0 270)
			(layer "F.SilkS")
			(hide yes)
			(effects
				(font
					(size 1.27 1.27)
				)
			)
		)
		(property "Value" ""
			(at 0 0 270)
			(layer "F.Fab")
			(effects
				(font
					(size 1.27 1.27)
				)
			)
		)
		(duplicate_pad_numbers_are_jumpers no)
		(fp_line
			(start -0.7874 0.4064)
			(end -0.7874 -0.4064)
			(stroke
				(width 0.1524)
				(type default)
			)
			(layer "F.SilkS")
		)
		(fp_line
			(start 0.7874 0.4064)
			(end -0.7874 0.4064)
			(stroke
				(width 0.1524)
				(type default)
			)
			(layer "F.SilkS")
		)
		(fp_line
			(start -0.7874 -0.4064)
			(end 0.7874 -0.4064)
			(stroke
				(width 0.1524)
				(type default)
			)
			(layer "F.SilkS")
		)
		(fp_line
			(start 0.7874 -0.4064)
			(end 0.7874 0.4064)
			(stroke
				(width 0.1524)
				(type default)
			)
			(layer "F.SilkS")
		)
		(fp_line
			(start -0.67945 0.3048)
			(end -0.67945 -0.305054)
			(stroke
				(width 0.1)
				(type default)
			)
			(layer "F.Fab")
		)
		(fp_line
			(start -0.12065 0.3048)
			(end -0.67945 0.3048)
			(stroke
				(width 0.1)
				(type default)
			)
			(layer "F.Fab")
		)
		(fp_line
			(start 0.120396 0.3048)
			(end 0.120396 0.2794)
			(stroke
				(width 0.1)
				(type default)
			)
			(layer "F.Fab")
		)
		(fp_line
			(start 0.67945 0.3048)
			(end 0.120396 0.3048)
			(stroke
				(width 0.1)
				(type default)
			)
			(layer "F.Fab")
		)
		(fp_line
			(start -0.12065 0.2794)
			(end -0.12065 0.3048)
			(stroke
				(width 0.1)
				(type default)
			)
			(layer "F.Fab")
		)
		(fp_line
			(start 0.120396 0.2794)
			(end -0.12065 0.2794)
			(stroke
				(width 0.1)
				(type default)
			)
			(layer "F.Fab")
		)
		(fp_line
			(start -0.12065 -0.2794)
			(end 0.12065 -0.2794)
			(stroke
				(width 0.1)
				(type default)
			)
			(layer "F.Fab")
		)
		(fp_line
			(start 0.12065 -0.2794)
			(end 0.12065 -0.3048)
			(stroke
				(width 0.1)
				(type default)
			)
			(layer "F.Fab")
		)
		(fp_line
			(start 0.12065 -0.3048)
			(end 0.67945 -0.3048)
			(stroke
				(width 0.1)
				(type default)
			)
			(layer "F.Fab")
		)
		(fp_line
			(start 0.67945 -0.3048)
			(end 0.67945 0.3048)
			(stroke
				(width 0.1)
				(type default)
			)
			(layer "F.Fab")
		)
		(fp_line
			(start -0.67945 -0.305054)
			(end -0.12065 -0.305054)
			(stroke
				(width 0.1)
				(type default)
			)
			(layer "F.Fab")
		)
		(fp_line
			(start -0.12065 -0.305054)
			(end -0.12065 -0.2794)
			(stroke
				(width 0.1)
				(type default)
			)
			(layer "F.Fab")
		)
		(pad "1" smd circle
			(at -0.40005 0 270)
			(size 0 0)
			(layers "F.Cu" "F.Mask" "F.Paste")
			(net "P12V_AUX")
		)
		(pad "2" smd circle
			(at 0.40005 0 270)
			(size 0 0)
			(layers "F.Cu" "F.Mask" "F.Paste")
			(net "GND")
		)
	)
)
